(kicad_pcb
	(version 20260206)
	(generator "pcbnew")
	(generator_version "10.0")
	(general
		(thickness 1.6)
		(legacy_teardrops no)
	)
	(paper "A4")
	(title_block
		(title "04192023_DAF0TMB3IC0_F0TG_MB_C_brd_V02_OCP.brd")
		(comment 1 "Grand Teton / footprints 768-773 of 8354")
	)
	(layers
		(0 "F.Cu" signal "TOP")
		(4 "In1.Cu" signal "GND")
		(6 "In2.Cu" signal "IN1")
		(8 "In3.Cu" signal "GND1")
		(10 "In4.Cu" signal "IN2")
		(12 "In5.Cu" signal "GND2")
		(14 "In6.Cu" signal "IN3")
		(16 "In7.Cu" signal "GND3")
		(18 "In8.Cu" signal "VCC")
		(20 "In9.Cu" signal "VCC1")
		(22 "In10.Cu" signal "GND4")
		(24 "In11.Cu" signal "IN4")
		(26 "In12.Cu" signal "GND5")
		(28 "In13.Cu" signal "IN5")
		(30 "In14.Cu" signal "GND6")
		(32 "In15.Cu" signal "IN6")
		(34 "In16.Cu" signal "GND7")
		(2 "B.Cu" signal "BOTTOM")
		(9 "F.Adhes" user "F.Adhesive")
		(11 "B.Adhes" user "B.Adhesive")
		(13 "F.Paste" user "Package Geometry/Pastemask Top")
		(15 "B.Paste" user "Package Geometry/Pastemask Bottom")
		(5 "F.SilkS" user "Ref Des/Silkscreen Top")
		(7 "B.SilkS" user "Ref Des/Silkscreen Bottom")
		(1 "F.Mask" user "Board Geometry/Soldermask Top")
		(3 "B.Mask" user "Board Geometry/Soldermask Bottom")
		(17 "Dwgs.User" user "User.Drawings")
		(19 "Cmts.User" user "User.Comments")
		(21 "Eco1.User" user "User.Eco1")
		(23 "Eco2.User" user "User.Eco2")
		(25 "Edge.Cuts" user "Board Geometry/Outline")
		(27 "Margin" user)
		(31 "F.CrtYd" user "Package Geometry/Place Bound Top")
		(29 "B.CrtYd" user "Package Geometry/Place Bound Bottom")
		(35 "F.Fab" user "Ref Des/Assembly Top")
		(33 "B.Fab" user "Ref Des/Assembly Bottom")
	)
	(footprint ""
		(layer "F.Cu")
		(at 185.862722 6.063234 180)
		(property "Reference" "J83"
			(at -4.472686 -1.101598 90)
			(unlocked yes)
			(layer "F.SilkS")
			(effects
				(font
					(size 0.7874 0.5842)
					(thickness 0.1524)
				)
				(justify left)
			)
		)
		(property "Value" ""
			(at 0 0 180)
			(layer "F.Fab")
			(effects
				(font
					(size 1.27 1.27)
				)
			)
		)
		(duplicate_pad_numbers_are_jumpers no)
		(fp_line
			(start 1.2192 2.06756)
			(end -1.2192 2.06756)
			(stroke
				(width 0.1524)
				(type default)
			)
			(layer "F.SilkS")
		)
		(fp_line
			(start 1.2192 -2.06756)
			(end 1.2192 2.06756)
			(stroke
				(width 0.1524)
				(type default)
			)
			(layer "F.SilkS")
		)
		(fp_line
			(start -1.2192 2.06756)
			(end -1.2192 -2.06756)
			(stroke
				(width 0.1524)
				(type default)
			)
			(layer "F.SilkS")
		)
		(fp_line
			(start -1.2192 -2.06756)
			(end 1.2192 -2.06756)
			(stroke
				(width 0.1524)
				(type default)
			)
			(layer "F.SilkS")
		)
		(pad "" np_thru_hole circle
			(at -2.8829 -1.27 90)
			(size 1.0414 1.0414)
			(drill 1.0414)
			(layers "*.Cu" "*.Mask")
			(clearance 0.381)
			(thermal_gap 0.381)
		)
		(pad "" np_thru_hole circle
			(at -2.8829 1.27 90)
			(size 1.0414 1.0414)
			(drill 1.0414)
			(layers "*.Cu" "*.Mask")
			(clearance 0.381)
			(thermal_gap 0.381)
		)
		(pad "" np_thru_hole circle
			(at 3.4671 -1.27 90)
			(size 1.0414 1.0414)
			(drill 1.0414)
			(layers "*.Cu" "*.Mask")
			(clearance 0.381)
			(thermal_gap 0.381)
		)
		(pad "" np_thru_hole circle
			(at 3.4671 1.27 90)
			(size 1.0414 1.0414)
			(drill 1.0414)
			(layers "*.Cu" "*.Mask")
			(clearance 0.381)
			(thermal_gap 0.381)
		)
		(pad "1" smd rect
			(at 0.8255 -0.249936 90)
			(size 0.3048 0.508)
			(layers "F.Cu" "F.Mask" "F.Paste")
			(net "DELTA_L_85_10INCH_IN1_DN")
		)
		(pad "2" smd rect
			(at 0.8255 0.249936 90)
			(size 0.3048 0.508)
			(layers "F.Cu" "F.Mask" "F.Paste")
			(net "DELTA_L_85_10INCH_IN1_DP")
		)
		(pad "3" smd circle
			(at 0 0 180)
			(size 0 0)
			(layers "F.Cu" "F.Mask" "F.Paste")
			(net "DELTA_L_GND_1")
		)
		(zone
			(layer "F.Cu")
			(hatch none 0.5)
			(connect_pads
				(clearance 0)
			)
			(min_thickness 0.25)
			(keepout
				(tracks not_allowed)
				(vias allowed)
				(pads allowed)
				(copperpour not_allowed)
				(footprints allowed)
			)
			(placement
				(enabled no)
				(sheetname "")
			)
			(fill
				(thermal_gap 0.5)
				(thermal_bridge_width 0.5)
				(island_removal_mode 0)
			)
			(polygon
				(pts
					(xy 184.745122 6.611874) (xy 184.745122 6.51637) (xy 185.342022 6.51637) (xy 185.342022 6.10997)
					(xy 184.745122 6.10997) (xy 184.745122 6.016498) (xy 185.342022 6.016498) (xy 185.342022 5.610098)
					(xy 184.745122 5.610098) (xy 184.745122 5.514594) (xy 185.443622 5.514594) (xy 185.443622 6.611874)
				)
			)
		)
		(zone
			(layers "F.Cu" "B.Cu" "In1.Cu" "In2.Cu" "In3.Cu" "In4.Cu" "In5.Cu" "In6.Cu"
				"In7.Cu" "In8.Cu" "In9.Cu" "In10.Cu" "In11.Cu" "In12.Cu" "In13.Cu" "In14.Cu"
				"In15.Cu" "In16.Cu"
			)
			(hatch none 0.5)
			(connect_pads
				(clearance 0)
			)
			(min_thickness 0.25)
			(keepout
				(tracks not_allowed)
				(vias allowed)
				(pads allowed)
				(copperpour not_allowed)
				(footprints allowed)
			)
			(placement
				(enabled no)
				(sheetname "")
			)
			(fill
				(thermal_gap 0.5)
				(thermal_bridge_width 0.5)
				(island_removal_mode 0)
			)
			(polygon
				(pts
					(arc
						(start 183.322722 4.793234)
						(mid 181.468522 4.793234)
						(end 183.322722 4.793234)
					)
				)
			)
		)
		(zone
			(layers "F.Cu" "B.Cu" "In1.Cu" "In2.Cu" "In3.Cu" "In4.Cu" "In5.Cu" "In6.Cu"
				"In7.Cu" "In8.Cu" "In9.Cu" "In10.Cu" "In11.Cu" "In12.Cu" "In13.Cu" "In14.Cu"
				"In15.Cu" "In16.Cu"
			)
			(hatch none 0.5)
			(connect_pads
				(clearance 0)
			)
			(min_thickness 0.25)
			(keepout
				(tracks not_allowed)
				(vias allowed)
				(pads allowed)
				(copperpour not_allowed)
				(footprints allowed)
			)
			(placement
				(enabled no)
				(sheetname "")
			)
			(fill
				(thermal_gap 0.5)
				(thermal_bridge_width 0.5)
				(island_removal_mode 0)
			)
			(polygon
				(pts
					(arc
						(start 183.322722 7.333234)
						(mid 181.468522 7.333234)
						(end 183.322722 7.333234)
					)
				)
			)
		)
		(zone
			(layers "F.Cu" "B.Cu" "In1.Cu" "In2.Cu" "In3.Cu" "In4.Cu" "In5.Cu" "In6.Cu"
				"In7.Cu" "In8.Cu" "In9.Cu" "In10.Cu" "In11.Cu" "In12.Cu" "In13.Cu" "In14.Cu"
				"In15.Cu" "In16.Cu"
			)
			(hatch none 0.5)
			(connect_pads
				(clearance 0)
			)
			(min_thickness 0.25)
			(keepout
				(tracks not_allowed)
				(vias allowed)
				(pads allowed)
				(copperpour not_allowed)
				(footprints allowed)
			)
			(placement
				(enabled no)
				(sheetname "")
			)
			(fill
				(thermal_gap 0.5)
				(thermal_bridge_width 0.5)
				(island_removal_mode 0)
			)
			(polygon
				(pts
					(arc
						(start 189.672722 4.793234)
						(mid 187.818522 4.793234)
						(end 189.672722 4.793234)
					)
				)
			)
		)
		(zone
			(layers "F.Cu" "B.Cu" "In1.Cu" "In2.Cu" "In3.Cu" "In4.Cu" "In5.Cu" "In6.Cu"
				"In7.Cu" "In8.Cu" "In9.Cu" "In10.Cu" "In11.Cu" "In12.Cu" "In13.Cu" "In14.Cu"
				"In15.Cu" "In16.Cu"
			)
			(hatch none 0.5)
			(connect_pads
				(clearance 0)
			)
			(min_thickness 0.25)
			(keepout
				(tracks not_allowed)
				(vias allowed)
				(pads allowed)
				(copperpour not_allowed)
				(footprints allowed)
			)
			(placement
				(enabled no)
				(sheetname "")
			)
			(fill
				(thermal_gap 0.5)
				(thermal_bridge_width 0.5)
				(island_removal_mode 0)
			)
			(polygon
				(pts
					(arc
						(start 189.672722 7.333234)
						(mid 187.818522 7.333234)
						(end 189.672722 7.333234)
					)
				)
			)
		)
	)
	(footprint ""
		(layer "F.Cu")
		(at 184.705752 -355.898958 -90)
		(property "Reference" "PC519"
			(at 0 0 270)
			(layer "F.SilkS")
			(hide yes)
			(effects
				(font
					(size 1.27 1.27)
				)
			)
		)
		(property "Value" ""
			(at 0 0 270)
			(layer "F.Fab")
			(effects
				(font
					(size 1.27 1.27)
				)
			)
		)
		(duplicate_pad_numbers_are_jumpers no)
		(fp_line
			(start -0.7874 0.4064)
			(end -0.7874 -0.4064)
			(stroke
				(width 0.1524)
				(type default)
			)
			(layer "F.SilkS")
		)
		(fp_line
			(start 0.7874 0.4064)
			(end -0.7874 0.4064)
			(stroke
				(width 0.1524)
				(type default)
			)
			(layer "F.SilkS")
		)
		(fp_line
			(start -0.7874 -0.4064)
			(end 0.7874 -0.4064)
			(stroke
				(width 0.1524)
				(type default)
			)
			(layer "F.SilkS")
		)
		(fp_line
			(start 0.7874 -0.4064)
			(end 0.7874 0.4064)
			(stroke
				(width 0.1524)
				(type default)
			)
			(layer "F.SilkS")
		)
		(fp_line
			(start -0.67945 0.3048)
			(end -0.67945 -0.305054)
			(stroke
				(width 0.1)
				(type default)
			)
			(layer "F.Fab")
		)
		(fp_line
			(start -0.12065 0.3048)
			(end -0.67945 0.3048)
			(stroke
				(width 0.1)
				(type default)
			)
			(layer "F.Fab")
		)
		(fp_line
			(start 0.120396 0.3048)
			(end 0.120396 0.2794)
			(stroke
				(width 0.1)
				(type default)
			)
			(layer "F.Fab")
		)
		(fp_line
			(start 0.67945 0.3048)
			(end 0.120396 0.3048)
			(stroke
				(width 0.1)
				(type default)
			)
			(layer "F.Fab")
		)
		(fp_line
			(start -0.12065 0.2794)
			(end -0.12065 0.3048)
			(stroke
				(width 0.1)
				(type default)
			)
			(layer "F.Fab")
		)
		(fp_line
			(start 0.120396 0.2794)
			(end -0.12065 0.2794)
			(stroke
				(width 0.1)
				(type default)
			)
			(layer "F.Fab")
		)
		(fp_line
			(start -0.12065 -0.2794)
			(end 0.12065 -0.2794)
			(stroke
				(width 0.1)
				(type default)
			)
			(layer "F.Fab")
		)
		(fp_line
			(start 0.12065 -0.2794)
			(end 0.12065 -0.3048)
			(stroke
				(width 0.1)
				(type default)
			)
			(layer "F.Fab")
		)
		(fp_line
			(start 0.12065 -0.3048)
			(end 0.67945 -0.3048)
			(stroke
				(width 0.1)
				(type default)
			)
			(layer "F.Fab")
		)
		(fp_line
			(start 0.67945 -0.3048)
			(end 0.67945 0.3048)
			(stroke
				(width 0.1)
				(type default)
			)
			(layer "F.Fab")
		)
		(fp_line
			(start -0.67945 -0.305054)
			(end -0.12065 -0.305054)
			(stroke
				(width 0.1)
				(type default)
			)
			(layer "F.Fab")
		)
		(fp_line
			(start -0.12065 -0.305054)
			(end -0.12065 -0.2794)
			(stroke
				(width 0.1)
				(type default)
			)
			(layer "F.Fab")
		)
		(pad "1" smd circle
			(at -0.40005 0 270)
			(size 0 0)
			(layers "F.Cu" "F.Mask" "F.Paste")
			(net "SW_PVDD11_S3_P1_BOOT1_RC")
		)
		(pad "2" smd circle
			(at 0.40005 0 270)
			(size 0 0)
			(layers "F.Cu" "F.Mask" "F.Paste")
			(net "SW_PVDD11_S3_P1_PH1")
		)
	)
	(footprint ""
		(layer "F.Cu")
		(at 79.629 -64.008 -90)
		(property "Reference" "U8002"
			(at 1.048766 -2.816606 90)
			(unlocked yes)
			(layer "F.SilkS")
			(effects
				(font
					(size 0.7874 0.5842)
					(thickness 0.1524)
				)
				(justify left)
			)
		)
		(property "Value" ""
			(at 0 0 270)
			(layer "F.Fab")
			(effects
				(font
					(size 1.27 1.27)
				)
			)
		)
		(duplicate_pad_numbers_are_jumpers no)
		(fp_line
			(start -1.759712 1.500124)
			(end -1.759712 -1.500124)
			(stroke
				(width 0.1524)
				(type default)
			)
			(layer "F.SilkS")
		)
		(fp_line
			(start 1.759712 1.500124)
			(end -1.759712 1.500124)
			(stroke
				(width 0.1524)
				(type default)
			)
			(layer "F.SilkS")
		)
		(fp_line
			(start -1.759712 -1.500124)
			(end 1.759712 -1.500124)
			(stroke
				(width 0.1524)
				(type default)
			)
			(layer "F.SilkS")
		)
		(fp_line
			(start 1.759712 -1.500124)
			(end 1.759712 1.500124)
			(stroke
				(width 0.1524)
				(type default)
			)
			(layer "F.SilkS")
		)
		(fp_line
			(start -0.700024 1.500124)
			(end -0.700024 -1.500124)
			(stroke
				(width 0.1)
				(type default)
			)
			(layer "F.Fab")
		)
		(fp_line
			(start 0.700024 1.500124)
			(end -0.700024 1.500124)
			(stroke
				(width 0.1)
				(type default)
			)
			(layer "F.Fab")
		)
		(fp_line
			(start -0.700024 -1.500124)
			(end 0.700024 -1.500124)
			(stroke
				(width 0.1)
				(type default)
			)
			(layer "F.Fab")
		)
		(fp_line
			(start 0.700024 -1.500124)
			(end 0.700024 1.500124)
			(stroke
				(width 0.1)
				(type default)
			)
			(layer "F.Fab")
		)
		(pad "1" smd rect
			(at -1.150112 -0.94996 180)
			(size 0.6604 0.9652)
			(layers "F.Cu" "F.Mask" "F.Paste")
			(net "GND")
		)
		(pad "2" smd rect
			(at -1.150112 0.94996 180)
			(size 0.6604 0.9652)
			(layers "F.Cu" "F.Mask" "F.Paste")
			(net "OCP_V3_2_P3V3_R1_PWRGD")
		)
		(pad "3" smd rect
			(at 1.150112 0 180)
			(size 0.6604 0.9652)
			(layers "F.Cu" "F.Mask" "F.Paste")
			(net "P3V3_OCP_V3_2_R")
		)
	)
	(footprint ""
		(layer "F.Cu")
		(at 275.574252 -119.91467)
		(property "Reference" "R6211"
			(at 0 0 0)
			(layer "F.SilkS")
			(hide yes)
			(effects
				(font
					(size 1.27 1.27)
				)
			)
		)
		(property "Value" ""
			(at 0 0 0)
			(layer "F.Fab")
			(effects
				(font
					(size 1.27 1.27)
				)
			)
		)
		(duplicate_pad_numbers_are_jumpers no)
		(fp_line
			(start -0.7874 -0.4064)
			(end 0.7874 -0.4064)
			(stroke
				(width 0.1524)
				(type default)
			)
			(layer "F.SilkS")
		)
		(fp_line
			(start -0.7874 0.4064)
			(end -0.7874 -0.4064)
			(stroke
				(width 0.1524)
				(type default)
			)
			(layer "F.SilkS")
		)
		(fp_line
			(start 0.7874 -0.4064)
			(end 0.7874 0.4064)
			(stroke
				(width 0.1524)
				(type default)
			)
			(layer "F.SilkS")
		)
		(fp_line
			(start 0.7874 0.4064)
			(end -0.7874 0.4064)
			(stroke
				(width 0.1524)
				(type default)
			)
			(layer "F.SilkS")
		)
		(fp_line
			(start -0.67945 -0.305054)
			(end -0.12065 -0.305054)
			(stroke
				(width 0.1)
				(type default)
			)
			(layer "F.Fab")
		)
		(fp_line
			(start -0.67945 0.3048)
			(end -0.67945 -0.305054)
			(stroke
				(width 0.1)
				(type default)
			)
			(layer "F.Fab")
		)
		(fp_line
			(start -0.12065 -0.305054)
			(end -0.12065 -0.2794)
			(stroke
				(width 0.1)
				(type default)
			)
			(layer "F.Fab")
		)
		(fp_line
			(start -0.12065 -0.2794)
			(end 0.12065 -0.2794)
			(stroke
				(width 0.1)
				(type default)
			)
			(layer "F.Fab")
		)
		(fp_line
			(start -0.12065 0.2794)
			(end -0.12065 0.3048)
			(stroke
				(width 0.1)
				(type default)
			)
			(layer "F.Fab")
		)
		(fp_line
			(start -0.12065 0.3048)
			(end -0.67945 0.3048)
			(stroke
				(width 0.1)
				(type default)
			)
			(layer "F.Fab")
		)
		(fp_line
			(start 0.120396 0.2794)
			(end -0.12065 0.2794)
			(stroke
				(width 0.1)
				(type default)
			)
			(layer "F.Fab")
		)
		(fp_line
			(start 0.120396 0.3048)
			(end 0.120396 0.2794)
			(stroke
				(width 0.1)
				(type default)
			)
			(layer "F.Fab")
		)
		(fp_line
			(start 0.12065 -0.3048)
			(end 0.67945 -0.3048)
			(stroke
				(width 0.1)
				(type default)
			)
			(layer "F.Fab")
		)
		(fp_line
			(start 0.12065 -0.2794)
			(end 0.12065 -0.3048)
			(stroke
				(width 0.1)
				(type default)
			)
			(layer "F.Fab")
		)
		(fp_line
			(start 0.67945 -0.3048)
			(end 0.67945 0.3048)
			(stroke
				(width 0.1)
				(type default)
			)
			(layer "F.Fab")
		)
		(fp_line
			(start 0.67945 0.3048)
			(end 0.120396 0.3048)
			(stroke
				(width 0.1)
				(type default)
			)
			(layer "F.Fab")
		)
		(pad "1" smd circle
			(at -0.40005 0)
			(size 0 0)
			(layers "F.Cu" "F.Mask" "F.Paste")
			(net "P3V3_AUX")
		)
		(pad "2" smd circle
			(at 0.40005 0)
			(size 0 0)
			(layers "F.Cu" "F.Mask" "F.Paste")
			(net "SMB_USB_CPU0_HUB1_SCL")
		)
	)
	(footprint ""
		(layer "F.Cu")
		(at 180.3908 -394.1318)
		(property "Reference" "R1417"
			(at 0 0 0)
			(layer "F.SilkS")
			(hide yes)
			(effects
				(font
					(size 1.27 1.27)
				)
			)
		)
		(property "Value" ""
			(at 0 0 0)
			(layer "F.Fab")
			(effects
				(font
					(size 1.27 1.27)
				)
			)
		)
		(duplicate_pad_numbers_are_jumpers no)
		(fp_line
			(start -0.32512 -0.175006)
			(end 0.32512 -0.175006)
			(stroke
				(width 0.1)
				(type default)
			)
			(layer "F.Fab")
		)
		(fp_line
			(start -0.32512 0.175006)
			(end -0.32512 -0.175006)
			(stroke
				(width 0.1)
				(type default)
			)
			(layer "F.Fab")
		)
		(fp_line
			(start 0.32512 -0.175006)
			(end 0.32512 0.175006)
			(stroke
				(width 0.1)
				(type default)
			)
			(layer "F.Fab")
		)
		(fp_line
			(start 0.32512 0.175006)
			(end -0.32512 0.175006)
			(stroke
				(width 0.1)
				(type default)
			)
			(layer "F.Fab")
		)
		(pad "1" smd rect
			(at -0.2667 0)
			(size 0.3048 0.381)
			(layers "F.Cu" "F.Mask" "F.Paste")
			(net "JTAG_TCK_RT_CPU1_P2")
		)
		(pad "2" smd rect
			(at 0.2667 0 180)
			(size 0.3048 0.381)
			(layers "F.Cu" "F.Mask" "F.Paste")
			(net "GND")
		)
	)
	(footprint ""
		(layer "F.Cu")
		(at 33.203896 -344.986864 90)
		(property "Reference" "PR492"
			(at 0 0 90)
			(layer "F.SilkS")
			(hide yes)
			(effects
				(font
					(size 1.27 1.27)
				)
			)
		)
		(property "Value" ""
			(at 0 0 90)
			(layer "F.Fab")
			(effects
				(font
					(size 1.27 1.27)
				)
			)
		)
		(duplicate_pad_numbers_are_jumpers no)
		(fp_line
			(start 0.7874 -0.4064)
			(end 0.7874 0.4064)
			(stroke
				(width 0.1524)
				(type default)
			)
			(layer "F.SilkS")
		)
		(fp_line
			(start -0.7874 -0.4064)
			(end 0.7874 -0.4064)
			(stroke
				(width 0.1524)
				(type default)
			)
			(layer "F.SilkS")
		)
		(fp_line
			(start 0.7874 0.4064)
			(end -0.7874 0.4064)
			(stroke
				(width 0.1524)
				(type default)
			)
			(layer "F.SilkS")
		)
		(fp_line
			(start -0.7874 0.4064)
			(end -0.7874 -0.4064)
			(stroke
				(width 0.1524)
				(type default)
			)
			(layer "F.SilkS")
		)
		(fp_line
			(start -0.12065 -0.305054)
			(end -0.12065 -0.2794)
			(stroke
				(width 0.1)
				(type default)
			)
			(layer "F.Fab")
		)
		(fp_line
			(start -0.67945 -0.305054)
			(end -0.12065 -0.305054)
			(stroke
				(width 0.1)
				(type default)
			)
			(layer "F.Fab")
		)
		(fp_line
			(start 0.67945 -0.3048)
			(end 0.67945 0.3048)
			(stroke
				(width 0.1)
				(type default)
			)
			(layer "F.Fab")
		)
		(fp_line
			(start 0.12065 -0.3048)
			(end 0.67945 -0.3048)
			(stroke
				(width 0.1)
				(type default)
			)
			(layer "F.Fab")
		)
		(fp_line
			(start 0.12065 -0.2794)
			(end 0.12065 -0.3048)
			(stroke
				(width 0.1)
				(type default)
			)
			(layer "F.Fab")
		)
		(fp_line
			(start -0.12065 -0.2794)
			(end 0.12065 -0.2794)
			(stroke
				(width 0.1)
				(type default)
			)
			(layer "F.Fab")
		)
		(fp_line
			(start 0.120396 0.2794)
			(end -0.12065 0.2794)
			(stroke
				(width 0.1)
				(type default)
			)
			(layer "F.Fab")
		)
		(fp_line
			(start -0.12065 0.2794)
			(end -0.12065 0.3048)
			(stroke
				(width 0.1)
				(type default)
			)
			(layer "F.Fab")
		)
		(fp_line
			(start 0.67945 0.3048)
			(end 0.120396 0.3048)
			(stroke
				(width 0.1)
				(type default)
			)
			(layer "F.Fab")
		)
		(fp_line
			(start 0.120396 0.3048)
			(end 0.120396 0.2794)
			(stroke
				(width 0.1)
				(type default)
			)
			(layer "F.Fab")
		)
		(fp_line
			(start -0.12065 0.3048)
			(end -0.67945 0.3048)
			(stroke
				(width 0.1)
				(type default)
			)
			(layer "F.Fab")
		)
		(fp_line
			(start -0.67945 0.3048)
			(end -0.67945 -0.305054)
			(stroke
				(width 0.1)
				(type default)
			)
			(layer "F.Fab")
		)
		(pad "1" smd circle
			(at -0.40005 0 90)
			(size 0 0)
			(layers "F.Cu" "F.Mask" "F.Paste")
			(net "SW_PVDDIO_P1_SW3_RC")
		)
		(pad "2" smd circle
			(at 0.40005 0 90)
			(size 0 0)
			(layers "F.Cu" "F.Mask" "F.Paste")
			(net "GND")
		)
	)
)
